(kicad_pcb
	(version 20260206)
	(generator "pcbnew")
	(generator_version "10.0")
	(general
		(thickness 1.6)
		(legacy_teardrops no)
	)
	(paper "A4")
	(title_block
		(title "Bryce Canyon_IOM_M2_16342-2_OCP.brd")
		(comment 1 "Bryce Canyon / footprints 258-265 of 1146")
	)
	(layers
		(0 "F.Cu" signal "TOP")
		(4 "In1.Cu" signal "L2GND")
		(6 "In2.Cu" signal "L3")
		(8 "In3.Cu" signal "L4VCC")
		(10 "In4.Cu" signal "L5VCC")
		(12 "In5.Cu" signal "L6")
		(14 "In6.Cu" signal "L7GND")
		(2 "B.Cu" signal "BOTTOM")
		(9 "F.Adhes" user "F.Adhesive")
		(11 "B.Adhes" user "B.Adhesive")
		(13 "F.Paste" user "Package Geometry/Pastemask Top")
		(15 "B.Paste" user "Package Geometry/Pastemask Bottom")
		(5 "F.SilkS" user "Ref Des/Silkscreen Top")
		(7 "B.SilkS" user "Ref Des/Silkscreen Bottom")
		(1 "F.Mask" user "Board Geometry/Soldermask Top")
		(3 "B.Mask" user "Board Geometry/Soldermask Bottom")
		(17 "Dwgs.User" user "User.Drawings")
		(19 "Cmts.User" user "User.Comments")
		(21 "Eco1.User" user "User.Eco1")
		(23 "Eco2.User" user "User.Eco2")
		(25 "Edge.Cuts" user "Board Geometry/Outline")
		(27 "Margin" user)
		(31 "F.CrtYd" user "Package Geometry/Place Bound Top")
		(29 "B.CrtYd" user "Package Geometry/Place Bound Bottom")
		(35 "F.Fab" user "Ref Des/Assembly Top")
		(33 "B.Fab" user "Ref Des/Assembly Bottom")
	)
	(footprint ""
		(layer "F.Cu")
		(at 17.723612 -131.007358 180)
		(property "Reference" "R221"
			(at 0 0 180)
			(layer "F.SilkS")
			(hide yes)
			(effects
				(font
					(size 1.27 1.27)
				)
			)
		)
		(property "Value" "120R2F-GP"
			(at 0.064008 -3.993896 180)
			(unlocked yes)
			(layer "F.Fab")
			(hide yes)
			(effects
				(font
					(size 1.016 1.016)
					(thickness 0.1524)
				)
			)
		)
		(property "Device Type" "R402H16"
			(at 0.064008 -5.517896 180)
			(unlocked yes)
			(layer "F.Fab")
			(hide yes)
			(effects
				(font
					(size 1.016 1.016)
					(thickness 0.1524)
				)
			)
		)
		(duplicate_pad_numbers_are_jumpers no)
		(fp_line
			(start 0.508 -0.9398)
			(end -0.508 -0.9398)
			(stroke
				(width 0.1524)
				(type default)
			)
			(layer "F.SilkS")
		)
		(fp_line
			(start -0.508 -0.9398)
			(end -0.508 0.9398)
			(stroke
				(width 0.1524)
				(type default)
			)
			(layer "F.SilkS")
		)
		(fp_rect
			(start -0.508 0.9398)
			(end 0.508 -0.9398)
			(stroke
				(width 0)
				(type default)
			)
			(fill no)
			(layer "F.CrtYd")
		)
		(fp_rect
			(start -0.508 0.9398)
			(end 0.508 -0.9398)
			(stroke
				(width 0)
				(type default)
			)
			(fill no)
			(layer "F.Fab")
		)
		(pad "1" smd custom
			(at 0 -0.4445 180)
			(size 0.1397 0.1397)
			(layers "F.Cu" "F.Mask" "F.Paste")
			(net "DDR4_ACT")
			(options
				(clearance outline)
				(anchor circle)
			)
			(primitives
				(gr_poly
					(pts
						(arc
							(start -0.1778 -0.2794)
							(mid -0.249642 -0.249642)
							(end -0.2794 -0.1778)
						)
						(arc
							(start -0.2794 0.1778)
							(mid -0.249642 0.249642)
							(end -0.1778 0.2794)
						)
						(arc
							(start 0.1778 0.2794)
							(mid 0.249642 0.249642)
							(end 0.2794 0.1778)
						)
						(arc
							(start 0.2794 -0.1778)
							(mid 0.249642 -0.249642)
							(end 0.1778 -0.2794)
						)
					)
					(width 0)
					(fill yes)
				)
			)
		)
		(pad "2" smd custom
			(at 0 0.4445 180)
			(size 0.1397 0.1397)
			(layers "F.Cu" "F.Mask" "F.Paste")
			(net "P1V2_STBY")
			(options
				(clearance outline)
				(anchor circle)
			)
			(primitives
				(gr_poly
					(pts
						(arc
							(start -0.1778 -0.2794)
							(mid -0.249642 -0.249642)
							(end -0.2794 -0.1778)
						)
						(arc
							(start -0.2794 0.1778)
							(mid -0.249642 0.249642)
							(end -0.1778 0.2794)
						)
						(arc
							(start 0.1778 0.2794)
							(mid 0.249642 0.249642)
							(end 0.2794 0.1778)
						)
						(arc
							(start 0.2794 -0.1778)
							(mid 0.249642 -0.249642)
							(end 0.1778 -0.2794)
						)
					)
					(width 0)
					(fill yes)
				)
			)
		)
	)
	(footprint ""
		(layer "F.Cu")
		(at 63.3476 -148.7678 90)
		(property "Reference" "R189"
			(at 0 0 90)
			(layer "F.SilkS")
			(hide yes)
			(effects
				(font
					(size 1.27 1.27)
				)
			)
		)
		(property "Value" "499R2F-2-GP"
			(at 0.064008 -3.993896 90)
			(unlocked yes)
			(layer "F.Fab")
			(hide yes)
			(effects
				(font
					(size 1.016 1.016)
					(thickness 0.1524)
				)
			)
		)
		(property "Device Type" "R402H16"
			(at 0.064008 -5.517896 90)
			(unlocked yes)
			(layer "F.Fab")
			(hide yes)
			(effects
				(font
					(size 1.016 1.016)
					(thickness 0.1524)
				)
			)
		)
		(duplicate_pad_numbers_are_jumpers no)
		(fp_line
			(start 0.508 -0.9398)
			(end -0.508 -0.9398)
			(stroke
				(width 0.1524)
				(type default)
			)
			(layer "F.SilkS")
		)
		(fp_line
			(start -0.508 -0.9398)
			(end -0.508 0.9398)
			(stroke
				(width 0.1524)
				(type default)
			)
			(layer "F.SilkS")
		)
		(fp_rect
			(start -0.508 0.9398)
			(end 0.508 -0.9398)
			(stroke
				(width 0)
				(type default)
			)
			(fill no)
			(layer "F.CrtYd")
		)
		(fp_rect
			(start -0.508 0.9398)
			(end 0.508 -0.9398)
			(stroke
				(width 0)
				(type default)
			)
			(fill no)
			(layer "F.Fab")
		)
		(pad "1" smd custom
			(at 0 -0.4445 90)
			(size 0.1397 0.1397)
			(layers "F.Cu" "F.Mask" "F.Paste")
			(net "I2C_BMC_COMP_SCL_OUT")
			(options
				(clearance outline)
				(anchor circle)
			)
			(primitives
				(gr_poly
					(pts
						(arc
							(start -0.1778 -0.2794)
							(mid -0.249642 -0.249642)
							(end -0.2794 -0.1778)
						)
						(arc
							(start -0.2794 0.1778)
							(mid -0.249642 0.249642)
							(end -0.1778 0.2794)
						)
						(arc
							(start 0.1778 0.2794)
							(mid 0.249642 0.249642)
							(end 0.2794 0.1778)
						)
						(arc
							(start 0.2794 -0.1778)
							(mid 0.249642 -0.249642)
							(end 0.1778 -0.2794)
						)
					)
					(width 0)
					(fill yes)
				)
			)
		)
		(pad "2" smd custom
			(at 0 0.4445 90)
			(size 0.1397 0.1397)
			(layers "F.Cu" "F.Mask" "F.Paste")
			(net "P3V3_STBY")
			(options
				(clearance outline)
				(anchor circle)
			)
			(primitives
				(gr_poly
					(pts
						(arc
							(start -0.1778 -0.2794)
							(mid -0.249642 -0.249642)
							(end -0.2794 -0.1778)
						)
						(arc
							(start -0.2794 0.1778)
							(mid -0.249642 0.249642)
							(end -0.1778 0.2794)
						)
						(arc
							(start 0.1778 0.2794)
							(mid 0.249642 0.249642)
							(end 0.2794 0.1778)
						)
						(arc
							(start 0.2794 -0.1778)
							(mid 0.249642 -0.249642)
							(end 0.1778 -0.2794)
						)
					)
					(width 0)
					(fill yes)
				)
			)
		)
	)
	(footprint ""
		(layer "F.Cu")
		(at 226.222306 -93.81744 180)
		(property "Reference" "C646"
			(at 0 0 180)
			(layer "F.SilkS")
			(hide yes)
			(effects
				(font
					(size 1.27 1.27)
				)
			)
		)
		(property "Value" "SC2200P50V2KX-2GP"
			(at 1.1811 -2.7051 180)
			(unlocked yes)
			(layer "F.Fab")
			(hide yes)
			(effects
				(font
					(size 1.016 1.016)
					(thickness 0.1524)
				)
			)
		)
		(property "Device Type" "C402H22"
			(at 1.1811 -4.2291 180)
			(unlocked yes)
			(layer "F.Fab")
			(hide yes)
			(effects
				(font
					(size 1.016 1.016)
					(thickness 0.1524)
				)
			)
		)
		(duplicate_pad_numbers_are_jumpers no)
		(fp_rect
			(start -0.4318 0.9525)
			(end 0.4318 -0.9525)
			(stroke
				(width 0)
				(type default)
			)
			(fill no)
			(layer "F.CrtYd")
		)
		(fp_rect
			(start -0.4318 0.9525)
			(end 0.4318 -0.9525)
			(stroke
				(width 0)
				(type default)
			)
			(fill no)
			(layer "F.Fab")
		)
		(pad "1" smd custom
			(at 0 -0.4445 180)
			(size 0.1524 0.1524)
			(layers "F.Cu" "F.Mask" "F.Paste")
			(net "P3V3_M2_LL")
			(options
				(clearance outline)
				(anchor circle)
			)
			(primitives
				(gr_poly
					(pts
						(arc
							(start 0.3048 -0.2032)
							(mid 0.275042 -0.275042)
							(end 0.2032 -0.3048)
						)
						(arc
							(start -0.2032 -0.3048)
							(mid -0.275042 -0.275042)
							(end -0.3048 -0.2032)
						)
						(arc
							(start -0.3048 0.2032)
							(mid -0.275042 0.275042)
							(end -0.2032 0.3048)
						)
						(arc
							(start 0.2032 0.3048)
							(mid 0.275042 0.275042)
							(end 0.3048 0.2032)
						)
					)
					(width 0)
					(fill yes)
				)
			)
		)
		(pad "2" smd custom
			(at 0 0.4445 180)
			(size 0.1524 0.1524)
			(layers "F.Cu" "F.Mask" "F.Paste")
			(net "P3V3_M2_SNB")
			(options
				(clearance outline)
				(anchor circle)
			)
			(primitives
				(gr_poly
					(pts
						(arc
							(start 0.3048 -0.2032)
							(mid 0.275042 -0.275042)
							(end 0.2032 -0.3048)
						)
						(arc
							(start -0.2032 -0.3048)
							(mid -0.275042 -0.275042)
							(end -0.3048 -0.2032)
						)
						(arc
							(start -0.3048 0.2032)
							(mid -0.275042 0.275042)
							(end -0.2032 0.3048)
						)
						(arc
							(start 0.2032 0.3048)
							(mid 0.275042 0.275042)
							(end 0.3048 0.2032)
						)
					)
					(width 0)
					(fill yes)
				)
			)
		)
	)
	(footprint ""
		(layer "F.Cu")
		(at 200.533 -141.224 -135)
		(property "Reference" "VIA54"
			(at 0 0 225)
			(layer "F.SilkS")
			(hide yes)
			(effects
				(font
					(size 1.27 1.27)
				)
			)
		)
		(property "Value" "85OHM-8L-1D6MM-L16L18-GP"
			(at 4.064105 0.609655 225)
			(unlocked yes)
			(layer "F.Fab")
			(hide yes)
			(effects
				(font
					(size 1.016 1.016)
					(thickness 0.1524)
				)
			)
		)
		(property "Device Type" "VIA-PCIE-4P-368076"
			(at 4.064105 -0.914474 225)
			(unlocked yes)
			(layer "F.Fab")
			(hide yes)
			(effects
				(font
					(size 1.016 1.016)
					(thickness 0.1524)
				)
			)
		)
		(duplicate_pad_numbers_are_jumpers no)
		(fp_poly
			(pts
				(xy -1.841491 -0.381057) (xy 1.841509 -0.381058) (xy 1.841508 0.380942) (xy -1.841491 0.380942)
			)
			(stroke
				(width 0)
				(type default)
			)
			(fill no)
			(layer "F.CrtYd")
		)
		(fp_poly
			(pts
				(xy -1.841491 -0.381057) (xy 1.841509 -0.381058) (xy 1.841508 0.380942) (xy -1.841491 0.380942)
			)
			(stroke
				(width 0)
				(type default)
			)
			(fill no)
			(layer "F.Fab")
		)
		(pad "1" thru_hole circle
			(at -1.460499 0 225)
			(size 0.508 0.508)
			(drill 0.254)
			(layers "*.Cu" "*.Mask")
			(remove_unused_layers no)
			(net "GND")
			(clearance 0.127)
			(thermal_gap 0.127)
		)
		(pad "2" thru_hole circle
			(at -0.4445 0 225)
			(size 0.508 0.508)
			(drill 0.254)
			(layers "*.Cu" "*.Mask")
			(remove_unused_layers no)
			(net "PCIE_COMP_TO_IOM_10_DP")
			(clearance 0.127)
			(thermal_gap 0.127)
		)
		(pad "3" thru_hole circle
			(at 0.4445 0 225)
			(size 0.508 0.508)
			(drill 0.254)
			(layers "*.Cu" "*.Mask")
			(remove_unused_layers no)
			(net "PCIE_COMP_TO_IOM_10_DN")
			(clearance 0.127)
			(thermal_gap 0.127)
		)
		(pad "4" thru_hole circle
			(at 1.460499 0 225)
			(size 0.508 0.508)
			(drill 0.254)
			(layers "*.Cu" "*.Mask")
			(remove_unused_layers no)
			(net "GND")
			(clearance 0.127)
			(thermal_gap 0.127)
		)
	)
	(footprint ""
		(layer "F.Cu")
		(at 63.119 -169.291 90)
		(property "Reference" "Q4"
			(at 0 0 90)
			(layer "F.SilkS")
			(hide yes)
			(effects
				(font
					(size 1.27 1.27)
				)
			)
		)
		(property "Value" "2N7002K-1-GP"
			(at 0.127 -8.9662 90)
			(unlocked yes)
			(layer "F.Fab")
			(hide yes)
			(effects
				(font
					(size 1.016 1.016)
					(thickness 0.1524)
				)
			)
		)
		(property "Device Type" "SOT23DGS2D4H44"
			(at 0.127 -10.4902 90)
			(unlocked yes)
			(layer "F.Fab")
			(hide yes)
			(effects
				(font
					(size 1.016 1.016)
					(thickness 0.1524)
				)
			)
		)
		(duplicate_pad_numbers_are_jumpers no)
		(fp_line
			(start 1.651 -1.778)
			(end -1.651 -1.778)
			(stroke
				(width 0.1524)
				(type default)
			)
			(layer "F.SilkS")
		)
		(fp_line
			(start -1.651 -1.778)
			(end -1.651 1.778)
			(stroke
				(width 0.1524)
				(type default)
			)
			(layer "F.SilkS")
		)
		(fp_line
			(start 1.651 1.778)
			(end 1.651 -1.778)
			(stroke
				(width 0.1524)
				(type default)
			)
			(layer "F.SilkS")
		)
		(fp_line
			(start -1.651 1.778)
			(end 1.651 1.778)
			(stroke
				(width 0.1524)
				(type default)
			)
			(layer "F.SilkS")
		)
		(fp_poly
			(pts
				(xy -1.778 1.8796) (xy -1.778 -1.8796) (xy 1.778 -1.8796) (xy 1.778 1.8796)
			)
			(stroke
				(width 0)
				(type default)
			)
			(fill no)
			(layer "F.CrtYd")
		)
		(fp_poly
			(pts
				(xy -1.778 1.8796) (xy -1.778 -1.8796) (xy 1.778 -1.8796) (xy 1.778 1.8796)
			)
			(stroke
				(width 0)
				(type default)
			)
			(fill no)
			(layer "F.Fab")
		)
		(pad "D" smd custom
			(at 0 -0.9525 90)
			(size 0.1905 0.1905)
			(layers "F.Cu" "F.Mask" "F.Paste")
			(net "FM_TPM_PRSNT_RST_N")
			(options
				(clearance outline)
				(anchor circle)
			)
			(primitives
				(gr_poly
					(pts
						(arc
							(start -0.1778 0.5715)
							(mid -0.321484 0.511984)
							(end -0.381 0.3683)
						)
						(arc
							(start -0.381 -0.3683)
							(mid -0.321484 -0.511984)
							(end -0.1778 -0.5715)
						)
						(arc
							(start 0.1778 -0.5715)
							(mid 0.321484 -0.511984)
							(end 0.381 -0.3683)
						)
						(arc
							(start 0.381 0.3683)
							(mid 0.321484 0.511984)
							(end 0.1778 0.5715)
						)
					)
					(width 0)
					(fill yes)
				)
			)
		)
		(pad "G" smd custom
			(at -0.98425 0.9525 90)
			(size 0.1905 0.1905)
			(layers "F.Cu" "F.Mask" "F.Paste")
			(net "Q4_G")
			(options
				(clearance outline)
				(anchor circle)
			)
			(primitives
				(gr_poly
					(pts
						(arc
							(start -0.1778 0.5715)
							(mid -0.321484 0.511984)
							(end -0.381 0.3683)
						)
						(arc
							(start -0.381 -0.3683)
							(mid -0.321484 -0.511984)
							(end -0.1778 -0.5715)
						)
						(arc
							(start 0.1778 -0.5715)
							(mid 0.321484 -0.511984)
							(end 0.381 -0.3683)
						)
						(arc
							(start 0.381 0.3683)
							(mid 0.321484 0.511984)
							(end 0.1778 0.5715)
						)
					)
					(width 0)
					(fill yes)
				)
			)
		)
		(pad "S" smd custom
			(at 0.98425 0.9525 90)
			(size 0.1905 0.1905)
			(layers "F.Cu" "F.Mask" "F.Paste")
			(net "GND")
			(options
				(clearance outline)
				(anchor circle)
			)
			(primitives
				(gr_poly
					(pts
						(arc
							(start -0.1778 0.5715)
							(mid -0.321484 0.511984)
							(end -0.381 0.3683)
						)
						(arc
							(start -0.381 -0.3683)
							(mid -0.321484 -0.511984)
							(end -0.1778 -0.5715)
						)
						(arc
							(start 0.1778 -0.5715)
							(mid 0.321484 -0.511984)
							(end 0.381 -0.3683)
						)
						(arc
							(start 0.381 0.3683)
							(mid 0.321484 0.511984)
							(end 0.1778 0.5715)
						)
					)
					(width 0)
					(fill yes)
				)
			)
		)
	)
	(footprint ""
		(layer "F.Cu")
		(at 20.582128 -131.007358 180)
		(property "Reference" "R226"
			(at 0 0 180)
			(layer "F.SilkS")
			(hide yes)
			(effects
				(font
					(size 1.27 1.27)
				)
			)
		)
		(property "Value" "120R2F-GP"
			(at 0.064008 -3.993896 180)
			(unlocked yes)
			(layer "F.Fab")
			(hide yes)
			(effects
				(font
					(size 1.016 1.016)
					(thickness 0.1524)
				)
			)
		)
		(property "Device Type" "R402H16"
			(at 0.064008 -5.517896 180)
			(unlocked yes)
			(layer "F.Fab")
			(hide yes)
			(effects
				(font
					(size 1.016 1.016)
					(thickness 0.1524)
				)
			)
		)
		(duplicate_pad_numbers_are_jumpers no)
		(fp_line
			(start 0.508 -0.9398)
			(end -0.508 -0.9398)
			(stroke
				(width 0.1524)
				(type default)
			)
			(layer "F.SilkS")
		)
		(fp_line
			(start -0.508 -0.9398)
			(end -0.508 0.9398)
			(stroke
				(width 0.1524)
				(type default)
			)
			(layer "F.SilkS")
		)
		(fp_rect
			(start -0.508 0.9398)
			(end 0.508 -0.9398)
			(stroke
				(width 0)
				(type default)
			)
			(fill no)
			(layer "F.CrtYd")
		)
		(fp_rect
			(start -0.508 0.9398)
			(end 0.508 -0.9398)
			(stroke
				(width 0)
				(type default)
			)
			(fill no)
			(layer "F.Fab")
		)
		(pad "1" smd custom
			(at 0 -0.4445 180)
			(size 0.1397 0.1397)
			(layers "F.Cu" "F.Mask" "F.Paste")
			(net "MEMCASN")
			(options
				(clearance outline)
				(anchor circle)
			)
			(primitives
				(gr_poly
					(pts
						(arc
							(start -0.1778 -0.2794)
							(mid -0.249642 -0.249642)
							(end -0.2794 -0.1778)
						)
						(arc
							(start -0.2794 0.1778)
							(mid -0.249642 0.249642)
							(end -0.1778 0.2794)
						)
						(arc
							(start 0.1778 0.2794)
							(mid 0.249642 0.249642)
							(end 0.2794 0.1778)
						)
						(arc
							(start 0.2794 -0.1778)
							(mid 0.249642 -0.249642)
							(end 0.1778 -0.2794)
						)
					)
					(width 0)
					(fill yes)
				)
			)
		)
		(pad "2" smd custom
			(at 0 0.4445 180)
			(size 0.1397 0.1397)
			(layers "F.Cu" "F.Mask" "F.Paste")
			(net "P1V2_STBY")
			(options
				(clearance outline)
				(anchor circle)
			)
			(primitives
				(gr_poly
					(pts
						(arc
							(start -0.1778 -0.2794)
							(mid -0.249642 -0.249642)
							(end -0.2794 -0.1778)
						)
						(arc
							(start -0.2794 0.1778)
							(mid -0.249642 0.249642)
							(end -0.1778 0.2794)
						)
						(arc
							(start 0.1778 0.2794)
							(mid 0.249642 0.249642)
							(end 0.2794 0.1778)
						)
						(arc
							(start 0.2794 -0.1778)
							(mid 0.249642 -0.249642)
							(end 0.1778 -0.2794)
						)
					)
					(width 0)
					(fill yes)
				)
			)
		)
	)
	(footprint ""
		(layer "F.Cu")
		(at 77.18298 -155.5369 -90)
		(property "Reference" "C234"
			(at 0 0 270)
			(layer "F.SilkS")
			(hide yes)
			(effects
				(font
					(size 1.27 1.27)
				)
			)
		)
		(property "Value" "SC1KP50V2KX-1GP"
			(at 1.1811 -2.7051 270)
			(unlocked yes)
			(layer "F.Fab")
			(hide yes)
			(effects
				(font
					(size 1.016 1.016)
					(thickness 0.1524)
				)
			)
		)
		(property "Device Type" "C402H22"
			(at 1.1811 -4.2291 270)
			(unlocked yes)
			(layer "F.Fab")
			(hide yes)
			(effects
				(font
					(size 1.016 1.016)
					(thickness 0.1524)
				)
			)
		)
		(duplicate_pad_numbers_are_jumpers no)
		(fp_rect
			(start -0.4318 0.9525)
			(end 0.4318 -0.9525)
			(stroke
				(width 0)
				(type default)
			)
			(fill no)
			(layer "F.CrtYd")
		)
		(fp_rect
			(start -0.4318 0.9525)
			(end 0.4318 -0.9525)
			(stroke
				(width 0)
				(type default)
			)
			(fill no)
			(layer "F.Fab")
		)
		(pad "1" smd custom
			(at 0 -0.4445 270)
			(size 0.1524 0.1524)
			(layers "F.Cu" "F.Mask" "F.Paste")
			(net "TPS74801_P1V15_STBY_OUT")
			(options
				(clearance outline)
				(anchor circle)
			)
			(primitives
				(gr_poly
					(pts
						(arc
							(start 0.3048 -0.2032)
							(mid 0.275042 -0.275042)
							(end 0.2032 -0.3048)
						)
						(arc
							(start -0.2032 -0.3048)
							(mid -0.275042 -0.275042)
							(end -0.3048 -0.2032)
						)
						(arc
							(start -0.3048 0.2032)
							(mid -0.275042 0.275042)
							(end -0.2032 0.3048)
						)
						(arc
							(start 0.2032 0.3048)
							(mid 0.275042 0.275042)
							(end 0.3048 0.2032)
						)
					)
					(width 0)
					(fill yes)
				)
			)
		)
		(pad "2" smd custom
			(at 0 0.4445 270)
			(size 0.1524 0.1524)
			(layers "F.Cu" "F.Mask" "F.Paste")
			(net "TPS74801_P1V15_STBY_FB")
			(options
				(clearance outline)
				(anchor circle)
			)
			(primitives
				(gr_poly
					(pts
						(arc
							(start 0.3048 -0.2032)
							(mid 0.275042 -0.275042)
							(end 0.2032 -0.3048)
						)
						(arc
							(start -0.2032 -0.3048)
							(mid -0.275042 -0.275042)
							(end -0.3048 -0.2032)
						)
						(arc
							(start -0.3048 0.2032)
							(mid -0.275042 0.275042)
							(end -0.2032 0.3048)
						)
						(arc
							(start 0.2032 0.3048)
							(mid 0.275042 0.275042)
							(end 0.3048 0.2032)
						)
					)
					(width 0)
					(fill yes)
				)
			)
		)
	)
	(footprint ""
		(layer "F.Cu")
		(at 59.857132 -135.702548)
		(property "Reference" "TP208"
			(at 0 0 0)
			(layer "F.SilkS")
			(hide yes)
			(effects
				(font
					(size 1.27 1.27)
				)
			)
		)
		(property "Value" "TPAD28-2-GP"
			(at -0.0127 -1.6637 0)
			(unlocked yes)
			(layer "F.Fab")
			(hide yes)
			(effects
				(font
					(size 1.016 1.016)
					(thickness 0.1524)
				)
			)
		)
		(property "Device Type" "TPAD28"
			(at -0.0127 -3.1877 0)
			(unlocked yes)
			(layer "F.Fab")
			(hide yes)
			(effects
				(font
					(size 1.016 1.016)
					(thickness 0.1524)
				)
			)
		)
		(duplicate_pad_numbers_are_jumpers no)
		(fp_poly
			(pts
				(arc
					(start 0.3556 0)
					(mid -0.3556 0)
					(end 0.3556 0)
				)
			)
			(stroke
				(width 0)
				(type default)
			)
			(fill no)
			(layer "F.CrtYd")
		)
		(fp_poly
			(pts
				(arc
					(start 0.6096 0)
					(mid -0.6096 0)
					(end 0.6096 0)
				)
			)
			(stroke
				(width 0)
				(type default)
			)
			(fill no)
			(layer "F.Fab")
		)
		(pad "1" smd circle
			(at 0 0)
			(size 0.7112 0.7112)
			(layers "F.Cu" "F.Mask" "F.Paste")
			(net "TP_BMC_EXT2_LED_G")
		)
	)
)
